# BASEBOARD_FAB2 (Tioga Pass) — schematic netlist excerpt (pin names and nets, part order shuffled) for the footprints in the layout excerpt that follows; sources: Cadence DE-HDL packaged netlist, KiCad conversion of Wiwynn_Tioga_Pass_MB.brd

C4A5  CAP_A  0.01UF 25V 10% X7R  pkg 0402V  page 54 : A = M_F_VREF ; B = GND
C8B6  CAP  10UF 16V 10% X6S  pkg 0805  page 198 : A = P5V ; B = GND
C4G15  CAP  1.0UF 16V 10% X6S  pkg 0402  page 221 : A = VR_PVTT_ABC_BIAS ; B = GND

(kicad_pcb
	(version 20260206)
	(generator "pcbnew")
	(generator_version "10.0")
	(general
		(thickness 1.6)
		(legacy_teardrops no)
	)
	(paper "A4")
	(title_block
		(title "Wiwynn_Tioga_Pass_MB.brd")
		(comment 1 "Tioga Pass / footprints 1490-1492 of 4770")
	)
	(layers
		(0 "F.Cu" signal "TOP")
		(4 "In1.Cu" signal "L2GND")
		(6 "In2.Cu" signal "L3")
		(8 "In3.Cu" signal "L4GND")
		(10 "In4.Cu" signal "L5")
		(12 "In5.Cu" signal "L6GND")
		(14 "In6.Cu" signal "L7VCC")
		(16 "In7.Cu" signal "L8VCC")
		(18 "In8.Cu" signal "L9GND")
		(20 "In9.Cu" signal "L10")
		(22 "In10.Cu" signal "L11GND")
		(24 "In11.Cu" signal "L12")
		(26 "In12.Cu" signal "L13GND")
		(2 "B.Cu" signal "BOTTOM")
		(9 "F.Adhes" user "F.Adhesive")
		(11 "B.Adhes" user "B.Adhesive")
		(13 "F.Paste" user "Package Geometry/Pastemask Top")
		(15 "B.Paste" user "Package Geometry/Pastemask Bottom")
		(5 "F.SilkS" user "Ref Des/Silkscreen Top")
		(7 "B.SilkS" user "Ref Des/Silkscreen Bottom")
		(1 "F.Mask" user "Board Geometry/Soldermask Top")
		(3 "B.Mask" user "Board Geometry/Soldermask Bottom")
		(17 "Dwgs.User" user "User.Drawings")
		(19 "Cmts.User" user "User.Comments")
		(21 "Eco1.User" user "User.Eco1")
		(23 "Eco2.User" user "User.Eco2")
		(25 "Edge.Cuts" user "Board Geometry/Outline")
		(27 "Margin" user)
		(31 "F.CrtYd" user "Package Geometry/Place Bound Top")
		(29 "B.CrtYd" user "Package Geometry/Place Bound Bottom")
		(35 "F.Fab" user "Ref Des/Assembly Top")
		(33 "B.Fab" user "Ref Des/Assembly Bottom")
	)
	(footprint ""
		(layer "F.Cu")
		(at 195.5292 -149.6568 90)
		(property "Reference" "C4A5"
			(at 0 0 90)
			(layer "F.SilkS")
			(hide yes)
			(effects
				(font
					(size 1.27 1.27)
				)
			)
		)
		(property "Value" ""
			(at 0 0 90)
			(layer "F.Fab")
			(effects
				(font
					(size 1.27 1.27)
				)
			)
		)
		(duplicate_pad_numbers_are_jumpers no)
		(fp_poly
			(pts
				(xy 0.3048 -0.1016) (xy 0.3048 0.9906) (xy -0.3048 0.9906) (xy -0.3048 -0.1016)
			)
			(stroke
				(width 0)
				(type default)
			)
			(fill no)
			(layer "F.CrtYd")
		)
		(fp_line
			(start 0.3048 -0.1016)
			(end -0.3048 -0.1016)
			(stroke
				(width 0.1)
				(type default)
			)
			(layer "F.Fab")
		)
		(fp_line
			(start -0.3048 -0.1016)
			(end -0.3048 0.9906)
			(stroke
				(width 0.1)
				(type default)
			)
			(layer "F.Fab")
		)
		(fp_line
			(start 0.3048 0.9906)
			(end 0.3048 -0.1016)
			(stroke
				(width 0.1)
				(type default)
			)
			(layer "F.Fab")
		)
		(fp_line
			(start -0.3048 0.9906)
			(end 0.3048 0.9906)
			(stroke
				(width 0.1)
				(type default)
			)
			(layer "F.Fab")
		)
		(pad "1" smd rect
			(at 0 0 90)
			(size 0.508 0.508)
			(layers "F.Cu" "F.Mask" "F.Paste")
			(net "M_F_VREF")
		)
		(pad "2" smd rect
			(at 0 0.889 90)
			(size 0.508 0.508)
			(layers "F.Cu" "F.Mask" "F.Paste")
			(net "GND")
		)
		(zone
			(layer "F.Cu")
			(hatch none 0.5)
			(connect_pads
				(clearance 0)
			)
			(min_thickness 0.25)
			(keepout
				(tracks allowed)
				(vias not_allowed)
				(pads allowed)
				(copperpour not_allowed)
				(footprints allowed)
			)
			(placement
				(enabled no)
				(sheetname "")
			)
			(fill
				(thermal_gap 0.5)
				(thermal_bridge_width 0.5)
				(island_removal_mode 0)
			)
			(polygon
				(pts
					(xy 195.7832 -149.4028) (xy 195.7832 -149.9108) (xy 196.1642 -149.9108) (xy 196.1642 -149.4028)
				)
			)
		)
		(zone
			(layer "F.Cu")
			(hatch none 0.5)
			(connect_pads
				(clearance 0)
			)
			(min_thickness 0.25)
			(keepout
				(tracks not_allowed)
				(vias allowed)
				(pads allowed)
				(copperpour not_allowed)
				(footprints allowed)
			)
			(placement
				(enabled no)
				(sheetname "")
			)
			(fill
				(thermal_gap 0.5)
				(thermal_bridge_width 0.5)
				(island_removal_mode 0)
			)
			(polygon
				(pts
					(xy 196.1642 -149.4028) (xy 196.1642 -149.9108) (xy 195.7832 -149.9108) (xy 195.7832 -149.4028)
				)
			)
		)
	)
	(footprint ""
		(layer "F.Cu")
		(at 183.388 -4.2545 180)
		(property "Reference" "C4G15"
			(at 0 0 180)
			(layer "F.SilkS")
			(hide yes)
			(effects
				(font
					(size 1.27 1.27)
				)
			)
		)
		(property "Value" ""
			(at 0 0 180)
			(layer "F.Fab")
			(effects
				(font
					(size 1.27 1.27)
				)
			)
		)
		(duplicate_pad_numbers_are_jumpers no)
		(fp_rect
			(start 0.3048 -0.1016)
			(end -0.3048 0.9906)
			(stroke
				(width 0)
				(type default)
			)
			(fill no)
			(layer "F.CrtYd")
		)
		(fp_line
			(start 0.3048 0.9906)
			(end 0.3048 -0.1016)
			(stroke
				(width 0.1)
				(type default)
			)
			(layer "F.Fab")
		)
		(fp_line
			(start 0.3048 -0.1016)
			(end -0.3048 -0.1016)
			(stroke
				(width 0.1)
				(type default)
			)
			(layer "F.Fab")
		)
		(fp_line
			(start -0.3048 0.9906)
			(end 0.3048 0.9906)
			(stroke
				(width 0.1)
				(type default)
			)
			(layer "F.Fab")
		)
		(fp_line
			(start -0.3048 -0.1016)
			(end -0.3048 0.9906)
			(stroke
				(width 0.1)
				(type default)
			)
			(layer "F.Fab")
		)
		(pad "1" smd rect
			(at 0 0 180)
			(size 0.508 0.508)
			(layers "F.Cu" "F.Mask" "F.Paste")
			(net "VR_PVTT_ABC_BIAS")
		)
		(pad "2" smd rect
			(at 0 0.889 180)
			(size 0.508 0.508)
			(layers "F.Cu" "F.Mask" "F.Paste")
			(net "GND")
		)
		(zone
			(layer "F.Cu")
			(hatch none 0.5)
			(connect_pads
				(clearance 0)
			)
			(min_thickness 0.25)
			(keepout
				(tracks not_allowed)
				(vias allowed)
				(pads allowed)
				(copperpour not_allowed)
				(footprints allowed)
			)
			(placement
				(enabled no)
				(sheetname "")
			)
			(fill
				(thermal_gap 0.5)
				(thermal_bridge_width 0.5)
				(island_removal_mode 0)
			)
			(polygon
				(pts
					(xy 183.134 -4.5085) (xy 183.642 -4.5085) (xy 183.642 -4.8895) (xy 183.134 -4.8895)
				)
			)
		)
		(zone
			(layer "F.Cu")
			(hatch none 0.5)
			(connect_pads
				(clearance 0)
			)
			(min_thickness 0.25)
			(keepout
				(tracks allowed)
				(vias not_allowed)
				(pads allowed)
				(copperpour not_allowed)
				(footprints allowed)
			)
			(placement
				(enabled no)
				(sheetname "")
			)
			(fill
				(thermal_gap 0.5)
				(thermal_bridge_width 0.5)
				(island_removal_mode 0)
			)
			(polygon
				(pts
					(xy 183.134 -4.5085) (xy 183.642 -4.5085) (xy 183.642 -4.8895) (xy 183.134 -4.8895)
				)
			)
		)
	)
	(footprint ""
		(layer "F.Cu")
		(at 439.3438 -128.778 180)
		(property "Reference" "C8B6"
			(at 0 0 180)
			(layer "F.SilkS")
			(hide yes)
			(effects
				(font
					(size 1.27 1.27)
				)
			)
		)
		(property "Value" ""
			(at 0 0 180)
			(layer "F.Fab")
			(effects
				(font
					(size 1.27 1.27)
				)
			)
		)
		(duplicate_pad_numbers_are_jumpers no)
		(fp_poly
			(pts
				(xy -0.7239 -0.2159) (xy 0.7239 -0.2159) (xy 0.7239 1.9939) (xy -0.7239 1.9939)
			)
			(stroke
				(width 0)
				(type default)
			)
			(fill no)
			(layer "F.CrtYd")
		)
		(fp_line
			(start 0.7239 1.9939)
			(end 0.7239 -0.2159)
			(stroke
				(width 0.1)
				(type default)
			)
			(layer "F.Fab")
		)
		(fp_line
			(start 0.7239 -0.2159)
			(end -0.7239 -0.2159)
			(stroke
				(width 0.1)
				(type default)
			)
			(layer "F.Fab")
		)
		(fp_line
			(start -0.7239 1.9939)
			(end 0.7239 1.9939)
			(stroke
				(width 0.1)
				(type default)
			)
			(layer "F.Fab")
		)
		(fp_line
			(start -0.7239 -0.2159)
			(end -0.7239 1.9939)
			(stroke
				(width 0.1)
				(type default)
			)
			(layer "F.Fab")
		)
		(pad "1" smd rect
			(at 0 0 180)
			(size 1.27 1.016)
			(layers "F.Cu" "F.Mask" "F.Paste")
			(net "P5V")
		)
		(pad "2" smd rect
			(at 0 1.778 180)
			(size 1.27 1.016)
			(layers "F.Cu" "F.Mask" "F.Paste")
			(net "GND")
		)
		(zone
			(layer "F.Cu")
			(hatch none 0.5)
			(connect_pads
				(clearance 0)
			)
			(min_thickness 0.25)
			(keepout
				(tracks not_allowed)
				(vias allowed)
				(pads allowed)
				(copperpour not_allowed)
				(footprints allowed)
			)
			(placement
				(enabled no)
				(sheetname "")
			)
			(fill
				(thermal_gap 0.5)
				(thermal_bridge_width 0.5)
				(island_removal_mode 0)
			)
			(polygon
				(pts
					(xy 439.9788 -129.286) (xy 438.7088 -129.286) (xy 438.7088 -130.048) (xy 439.9788 -130.048)
				)
			)
		)
	)
)
